# T6G (Grand Teton) — schematic netlist excerpt (pin names and nets, part order shuffled) for the footprints in the layout excerpt that follows; sources: Cadence DE-HDL packaged netlist, KiCad conversion of 04192023_DAF0TMB3IC0_F0TG_MB_C_brd_V02_OCP.brd

R3494  Q_RES  54.9K 1% CHIP  pkg 0402LF  page 129 : A = P3V3_AUX ; B = GPU_FPGA_EROT_RECOV_BUF_R_N
R1571  Q_RES  0 5% CHIP  pkg 0402LF  page 190 : A = PWRGD_P5V_AUX ; B = P3V3_AUX_EN

(kicad_pcb
	(version 20260206)
	(generator "pcbnew")
	(generator_version "10.0")
	(general
		(thickness 1.6)
		(legacy_teardrops no)
	)
	(paper "A4")
	(title_block
		(title "04192023_DAF0TMB3IC0_F0TG_MB_C_brd_V02_OCP.brd")
		(comment 1 "Grand Teton / footprints 3628-3629 of 8354")
	)
	(layers
		(0 "F.Cu" signal "TOP")
		(4 "In1.Cu" signal "GND")
		(6 "In2.Cu" signal "IN1")
		(8 "In3.Cu" signal "GND1")
		(10 "In4.Cu" signal "IN2")
		(12 "In5.Cu" signal "GND2")
		(14 "In6.Cu" signal "IN3")
		(16 "In7.Cu" signal "GND3")
		(18 "In8.Cu" signal "VCC")
		(20 "In9.Cu" signal "VCC1")
		(22 "In10.Cu" signal "GND4")
		(24 "In11.Cu" signal "IN4")
		(26 "In12.Cu" signal "GND5")
		(28 "In13.Cu" signal "IN5")
		(30 "In14.Cu" signal "GND6")
		(32 "In15.Cu" signal "IN6")
		(34 "In16.Cu" signal "GND7")
		(2 "B.Cu" signal "BOTTOM")
		(9 "F.Adhes" user "F.Adhesive")
		(11 "B.Adhes" user "B.Adhesive")
		(13 "F.Paste" user "Package Geometry/Pastemask Top")
		(15 "B.Paste" user "Package Geometry/Pastemask Bottom")
		(5 "F.SilkS" user "Ref Des/Silkscreen Top")
		(7 "B.SilkS" user "Ref Des/Silkscreen Bottom")
		(1 "F.Mask" user "Board Geometry/Soldermask Top")
		(3 "B.Mask" user "Board Geometry/Soldermask Bottom")
		(17 "Dwgs.User" user "User.Drawings")
		(19 "Cmts.User" user "User.Comments")
		(21 "Eco1.User" user "User.Eco1")
		(23 "Eco2.User" user "User.Eco2")
		(25 "Edge.Cuts" user "Board Geometry/Outline")
		(27 "Margin" user)
		(31 "F.CrtYd" user "Package Geometry/Place Bound Top")
		(29 "B.CrtYd" user "Package Geometry/Place Bound Bottom")
		(35 "F.Fab" user "Ref Des/Assembly Top")
		(33 "B.Fab" user "Ref Des/Assembly Bottom")
	)
	(footprint ""
		(layer "F.Cu")
		(at 120.396 -434.467 180)
		(property "Reference" "R3494"
			(at 0 0 180)
			(layer "F.SilkS")
			(hide yes)
			(effects
				(font
					(size 1.27 1.27)
				)
			)
		)
		(property "Value" ""
			(at 0 0 180)
			(layer "F.Fab")
			(effects
				(font
					(size 1.27 1.27)
				)
			)
		)
		(duplicate_pad_numbers_are_jumpers no)
		(fp_line
			(start 0.7874 0.4064)
			(end -0.7874 0.4064)
			(stroke
				(width 0.1524)
				(type default)
			)
			(layer "F.SilkS")
		)
		(fp_line
			(start 0.7874 -0.4064)
			(end 0.7874 0.4064)
			(stroke
				(width 0.1524)
				(type default)
			)
			(layer "F.SilkS")
		)
		(fp_line
			(start -0.7874 0.4064)
			(end -0.7874 -0.4064)
			(stroke
				(width 0.1524)
				(type default)
			)
			(layer "F.SilkS")
		)
		(fp_line
			(start -0.7874 -0.4064)
			(end 0.7874 -0.4064)
			(stroke
				(width 0.1524)
				(type default)
			)
			(layer "F.SilkS")
		)
		(fp_line
			(start 0.67945 0.3048)
			(end 0.120396 0.3048)
			(stroke
				(width 0.1)
				(type default)
			)
			(layer "F.Fab")
		)
		(fp_line
			(start 0.67945 -0.3048)
			(end 0.67945 0.3048)
			(stroke
				(width 0.1)
				(type default)
			)
			(layer "F.Fab")
		)
		(fp_line
			(start 0.12065 -0.2794)
			(end 0.12065 -0.3048)
			(stroke
				(width 0.1)
				(type default)
			)
			(layer "F.Fab")
		)
		(fp_line
			(start 0.12065 -0.3048)
			(end 0.67945 -0.3048)
			(stroke
				(width 0.1)
				(type default)
			)
			(layer "F.Fab")
		)
		(fp_line
			(start 0.120396 0.3048)
			(end 0.120396 0.2794)
			(stroke
				(width 0.1)
				(type default)
			)
			(layer "F.Fab")
		)
		(fp_line
			(start 0.120396 0.2794)
			(end -0.12065 0.2794)
			(stroke
				(width 0.1)
				(type default)
			)
			(layer "F.Fab")
		)
		(fp_line
			(start -0.12065 0.3048)
			(end -0.67945 0.3048)
			(stroke
				(width 0.1)
				(type default)
			)
			(layer "F.Fab")
		)
		(fp_line
			(start -0.12065 0.2794)
			(end -0.12065 0.3048)
			(stroke
				(width 0.1)
				(type default)
			)
			(layer "F.Fab")
		)
		(fp_line
			(start -0.12065 -0.2794)
			(end 0.12065 -0.2794)
			(stroke
				(width 0.1)
				(type default)
			)
			(layer "F.Fab")
		)
		(fp_line
			(start -0.12065 -0.305054)
			(end -0.12065 -0.2794)
			(stroke
				(width 0.1)
				(type default)
			)
			(layer "F.Fab")
		)
		(fp_line
			(start -0.67945 0.3048)
			(end -0.67945 -0.305054)
			(stroke
				(width 0.1)
				(type default)
			)
			(layer "F.Fab")
		)
		(fp_line
			(start -0.67945 -0.305054)
			(end -0.12065 -0.305054)
			(stroke
				(width 0.1)
				(type default)
			)
			(layer "F.Fab")
		)
		(pad "1" smd circle
			(at -0.40005 0 180)
			(size 0 0)
			(layers "F.Cu" "F.Mask" "F.Paste")
			(net "P3V3_AUX")
		)
		(pad "2" smd circle
			(at 0.40005 0 180)
			(size 0 0)
			(layers "F.Cu" "F.Mask" "F.Paste")
			(net "GPU_FPGA_EROT_RECOV_BUF_R_N")
		)
	)
	(footprint ""
		(layer "F.Cu")
		(at 452.13905 -48.462946)
		(property "Reference" "R1571"
			(at 0 0 0)
			(layer "F.SilkS")
			(hide yes)
			(effects
				(font
					(size 1.27 1.27)
				)
			)
		)
		(property "Value" ""
			(at 0 0 0)
			(layer "F.Fab")
			(effects
				(font
					(size 1.27 1.27)
				)
			)
		)
		(duplicate_pad_numbers_are_jumpers no)
		(fp_line
			(start -0.7874 -0.4064)
			(end 0.7874 -0.4064)
			(stroke
				(width 0.1524)
				(type default)
			)
			(layer "F.SilkS")
		)
		(fp_line
			(start -0.7874 0.4064)
			(end -0.7874 -0.4064)
			(stroke
				(width 0.1524)
				(type default)
			)
			(layer "F.SilkS")
		)
		(fp_line
			(start 0.7874 -0.4064)
			(end 0.7874 0.4064)
			(stroke
				(width 0.1524)
				(type default)
			)
			(layer "F.SilkS")
		)
		(fp_line
			(start 0.7874 0.4064)
			(end -0.7874 0.4064)
			(stroke
				(width 0.1524)
				(type default)
			)
			(layer "F.SilkS")
		)
		(fp_line
			(start -0.67945 -0.305054)
			(end -0.12065 -0.305054)
			(stroke
				(width 0.1)
				(type default)
			)
			(layer "F.Fab")
		)
		(fp_line
			(start -0.67945 0.3048)
			(end -0.67945 -0.305054)
			(stroke
				(width 0.1)
				(type default)
			)
			(layer "F.Fab")
		)
		(fp_line
			(start -0.12065 -0.305054)
			(end -0.12065 -0.2794)
			(stroke
				(width 0.1)
				(type default)
			)
			(layer "F.Fab")
		)
		(fp_line
			(start -0.12065 -0.2794)
			(end 0.12065 -0.2794)
			(stroke
				(width 0.1)
				(type default)
			)
			(layer "F.Fab")
		)
		(fp_line
			(start -0.12065 0.2794)
			(end -0.12065 0.3048)
			(stroke
				(width 0.1)
				(type default)
			)
			(layer "F.Fab")
		)
		(fp_line
			(start -0.12065 0.3048)
			(end -0.67945 0.3048)
			(stroke
				(width 0.1)
				(type default)
			)
			(layer "F.Fab")
		)
		(fp_line
			(start 0.120396 0.2794)
			(end -0.12065 0.2794)
			(stroke
				(width 0.1)
				(type default)
			)
			(layer "F.Fab")
		)
		(fp_line
			(start 0.120396 0.3048)
			(end 0.120396 0.2794)
			(stroke
				(width 0.1)
				(type default)
			)
			(layer "F.Fab")
		)
		(fp_line
			(start 0.12065 -0.3048)
			(end 0.67945 -0.3048)
			(stroke
				(width 0.1)
				(type default)
			)
			(layer "F.Fab")
		)
		(fp_line
			(start 0.12065 -0.2794)
			(end 0.12065 -0.3048)
			(stroke
				(width 0.1)
				(type default)
			)
			(layer "F.Fab")
		)
		(fp_line
			(start 0.67945 -0.3048)
			(end 0.67945 0.3048)
			(stroke
				(width 0.1)
				(type default)
			)
			(layer "F.Fab")
		)
		(fp_line
			(start 0.67945 0.3048)
			(end 0.120396 0.3048)
			(stroke
				(width 0.1)
				(type default)
			)
			(layer "F.Fab")
		)
		(pad "1" smd circle
			(at -0.40005 0)
			(size 0 0)
			(layers "F.Cu" "F.Mask" "F.Paste")
			(net "PWRGD_P5V_AUX")
		)
		(pad "2" smd circle
			(at 0.40005 0)
			(size 0 0)
			(layers "F.Cu" "F.Mask" "F.Paste")
			(net "P3V3_AUX_EN")
		)
	)
)
